#ISCELL
  mstr_misc dns *
  *
#ISCELL
  pure_quanta quanta_title_block_c *
  *
#ISCELL
  pure_quanta_power universal_gnd *
  page194_i1
#CELL
  pure_quanta q_cap *
  page194_i100
#CELL
  pure_quanta q_cap *
  page194_i101
#CELL
  pure_quanta q_res *
  page194_i102
#CELL
  pure_quanta q_cap *
  page194_i103
#CELL
  pure_quanta q_res *
  page194_i104
#CELL
  pure_quanta q_cap *
  page194_i105
#CELL
  pure_quanta q_cap *
  page194_i106
#CELL
  pure_quanta q_cap *
  page194_i107
#ISCELL
  pure_quanta_power universal_gnd *
  page194_i108
#ISCELL
  pure_quanta_power universal_gnd *
  page194_i109
#ISCELL
  pure_quanta_power universal_gnd *
  page194_i11
#CELL
  pure_quanta q_res *
  page194_i110
#CELL
  pure_quanta q_cap *
  page194_i111
#CELL
  pure_quanta q_cap *
  page194_i113
#ISCELL
  pure_quanta_power universal_gnd *
  page194_i114
#ISCELL
  pure_quanta_power universal_gnd *
  page194_i115
#CELL
  pure_quanta q_res *
  page194_i116
#CELL
  pure_quanta q_cap *
  page194_i117
#ISCELL
  pure_quanta_power universal_gnd *
  page194_i119
#ISCELL
  pure_quanta_power universal_gnd *
  page194_i120
#ISCELL
  pure_quanta_power universal_gnd *
  page194_i121
#CELL
  pure_quanta q_res *
  page194_i122
#CELL
  pure_quanta q_cap *
  page194_i123
#ISCELL
  pure_quanta_power universal_gnd *
  page194_i124
#CELL
  pure_quanta q_res *
  page194_i125
#CELL
  pure_quanta q_cap *
  page194_i126
#ISCELL
  pure_quanta_power universal_gnd *
  page194_i127
#ISCELL
  pure_quanta_power vcc_core *
  page194_i128
#ISCELL
  pure_quanta_power vcc_core *
  page194_i129
#CELL
  pure_quanta isl99390frztr5935 *
  page194_i14
#ISCELL
  pure_quanta_power universal_gnd *
  page194_i15
#ISCELL
  pure_quanta_power universal_gnd *
  page194_i18
#CELL
  pure_quanta q_res *
  page194_i19
#CELL
  pure_quanta q_res *
  page194_i2
#ISCELL
  standard offpage *
  page194_i21
#ISCELL
  standard offpage *
  page194_i22
#ISCELL
  standard offpage *
  page194_i23
#ISCELL
  standard offpage *
  page194_i24
#CELL
  pure_quanta isl99390frztr5935 *
  page194_i30
#CELL
  pure_quanta q_cap *
  page194_i37
#CELL
  pure_quanta q_cap *
  page194_i38
#ISCELL
  standard offpage *
  page194_i4
#CELL
  pure_quanta q_cap *
  page194_i40
#ISCELL
  pure_quanta_power universal_gnd *
  page194_i41
#CELL
  pure_quanta q_cap *
  page194_i42
#ISCELL
  pure_quanta_power vcc_core *
  page194_i43
#ISCELL
  standard offpage *
  page194_i5
#CELL
  pure_quanta q_cap *
  page194_i50
#CELL
  pure_quanta q_cap *
  page194_i51
#CELL
  pure_quanta q_cap *
  page194_i55
#CELL
  pure_quanta q_cap *
  page194_i56
#ISCELL
  pure_quanta_power universal_gnd *
  page194_i57
#ISCELL
  pure_quanta_power vcc_core *
  page194_i58
#ISCELL
  standard offpage *
  page194_i6
#ISCELL
  standard offpage *
  page194_i7
#ISCELL
  standard offpage *
  page194_i73
#ISCELL
  standard offpage *
  page194_i75
#CELL
  pure_quanta q_res *
  page194_i76
#ISCELL
  pure_quanta_power vcc_core *
  page194_i77
#CELL
  pure_quanta q_cap *
  page194_i78
#CELL
  pure_quanta q_cap *
  page194_i79
#ISCELL
  pure_quanta_power universal_gnd *
  page194_i80
#ISCELL
  standard offpage *
  page194_i91
#CELL
  pure_quanta q_res *
  page194_i92
#ISCELL
  pure_quanta_power vcc_core *
  page194_i93
#ISCELL
  pure_quanta_power universal_gnd *
  page194_i94
#CELL
  pure_quanta q_cap *
  page194_i95
#CELL
  pure_quanta q_cap *
  page194_i96
#CELL
  pure_quanta q_inductor4p_14 *
  page194_i97
#CELL
  pure_quanta q_inductor4p_14 *
  page194_i98
#CELL
  pure_quanta q_cap *
  page194_i99
